(kicad_pcb
	(version 20241229)
	(generator "pcbnew")
	(generator_version "9.0")
	(general
		(thickness 1.6642)
		(legacy_teardrops no)
	)
	(paper "A3")
	(title_block
		(title "PolarFire SoM")
		(date "2025-07-22")
		(rev "1.1.4")
		(company "Antmicro Ltd")
		(comment 1 "www.antmicro.com")
		(comment 9 "footprints 382-382 of 470")
	)
	(layers
		(0 "F.Cu" mixed)
		(4 "In1.Cu" power)
		(6 "In2.Cu" signal)
		(8 "In3.Cu" power)
		(10 "In4.Cu" signal)
		(12 "In5.Cu" power)
		(14 "In6.Cu" power)
		(16 "In7.Cu" signal)
		(18 "In8.Cu" power)
		(20 "In9.Cu" signal)
		(22 "In10.Cu" power)
		(24 "In11.Cu" signal)
		(26 "In12.Cu" signal)
		(2 "B.Cu" mixed)
		(9 "F.Adhes" user "F.Adhesive")
		(11 "B.Adhes" user "B.Adhesive")
		(13 "F.Paste" user)
		(15 "B.Paste" user)
		(5 "F.SilkS" user "F.Silkscreen")
		(7 "B.SilkS" user "B.Silkscreen")
		(1 "F.Mask" user)
		(3 "B.Mask" user)
		(17 "Dwgs.User" user "User.Drawings")
		(19 "Cmts.User" user "User.Comments")
		(21 "Eco1.User" user "User.Eco1")
		(23 "Eco2.User" user "User.Eco2")
		(25 "Edge.Cuts" user)
		(27 "Margin" user)
		(31 "F.CrtYd" user "F.Courtyard")
		(29 "B.CrtYd" user "B.Courtyard")
		(35 "F.Fab" user)
		(33 "B.Fab" user)
	)
	(footprint "antmicro-footprints:C_0402_1005Metric"
		(layer "B.Cu")
		(at 222.35 121.55 180)
		(descr "Capacitor SMD 0402")
		(tags "capacitor SMD 0402")
		(property "Reference" "C36"
			(at -1.05 1.95 0)
			(layer "B.SilkS")
			(effects
				(font
					(size 0.7 0.7)
					(thickness 0.15)
				)
				(justify left bottom mirror)
			)
		)
		(property "Value" "C_100n_0402"
			(at -1.022927 -2.155213 0)
			(layer "B.Fab")
			(hide yes)
			(effects
				(font
					(size 0.7 0.7)
					(thickness 0.15)
				)
				(justify left bottom mirror)
			)
		)
		(property "Datasheet" "https://www.murata.com/products/productdetail?partno=GRM155R61H104KE14%23"
			(at 0 0 180)
			(layer "F.Fab")
			(hide yes)
			(effects
				(font
					(size 1.27 1.27)
					(thickness 0.15)
				)
			)
		)
		(property "Description" "SMD Multilayer Ceramic Capacitor, 0.1 µF, 50 V, 0402 [1005 Metric], ± 10%, X5R, GRM Series"
			(at 0 0 180)
			(layer "F.Fab")
			(hide yes)
			(effects
				(font
					(size 1.27 1.27)
					(thickness 0.15)
				)
			)
		)
		(property "Author" "Antmicro"
			(at 444.7 243.1 0)
			(layer "B.Fab")
			(hide yes)
			(effects
				(font
					(size 1 1)
					(thickness 0.15)
				)
				(justify mirror)
			)
		)
		(property "Dielectric" "X5R"
			(at 444.7 243.1 0)
			(layer "B.Fab")
			(hide yes)
			(effects
				(font
					(size 1 1)
					(thickness 0.15)
				)
				(justify mirror)
			)
		)
		(property "License" "Apache-2.0"
			(at 444.7 243.1 0)
			(layer "B.Fab")
			(hide yes)
			(effects
				(font
					(size 1 1)
					(thickness 0.15)
				)
				(justify mirror)
			)
		)
		(property "MPN" "GRM155R61H104KE14D"
			(at 444.7 243.1 0)
			(layer "B.Fab")
			(hide yes)
			(effects
				(font
					(size 1 1)
					(thickness 0.15)
				)
				(justify mirror)
			)
		)
		(property "Manufacturer" "Murata"
			(at 444.7 243.1 0)
			(layer "B.Fab")
			(hide yes)
			(effects
				(font
					(size 1 1)
					(thickness 0.15)
				)
				(justify mirror)
			)
		)
		(property "Public" ""
			(at 444.7 243.1 0)
			(layer "B.Fab")
			(hide yes)
			(effects
				(font
					(size 1 1)
					(thickness 0.15)
				)
				(justify mirror)
			)
		)
		(property "Val" "100n"
			(at 444.7 243.1 0)
			(layer "B.Fab")
			(hide yes)
			(effects
				(font
					(size 1 1)
					(thickness 0.15)
				)
				(justify mirror)
			)
		)
		(property "Voltage" "50V"
			(at 444.7 243.1 0)
			(layer "B.Fab")
			(hide yes)
			(effects
				(font
					(size 1 1)
					(thickness 0.15)
				)
				(justify mirror)
			)
		)
		(sheetname "/FPGA GPIO/")
		(sheetfile "fpga-gpio.kicad_sch")
		(attr smd)
		(fp_rect
			(start -0.925 0.47)
			(end 0.925 -0.47)
			(stroke
				(width 0.05)
				(type default)
			)
			(fill no)
			(layer "B.CrtYd")
		)
		(fp_line
			(start 0.504 0.25)
			(end 0.504 -0.248)
			(stroke
				(width 0.15)
				(type solid)
			)
			(layer "B.Fab")
		)
		(fp_line
			(start 0.504 -0.248)
			(end -0.494 -0.248)
			(stroke
				(width 0.15)
				(type solid)
			)
			(layer "B.Fab")
		)
		(fp_line
			(start -0.494 0.25)
			(end 0.504 0.25)
			(stroke
				(width 0.15)
				(type solid)
			)
			(layer "B.Fab")
		)
		(fp_line
			(start -0.494 -0.248)
			(end -0.494 0.25)
			(stroke
				(width 0.15)
				(type solid)
			)
			(layer "B.Fab")
		)
		(fp_text user "${REFERENCE}"
			(at -0.939 -4.599 0)
			(layer "B.Fab")
			(effects
				(font
					(size 0.7 0.7)
					(thickness 0.15)
				)
				(justify left bottom mirror)
			)
		)
		(fp_text user "License: Apache-2.0"
			(at -0.939 -5.799 0)
			(layer "B.Fab")
			(effects
				(font
					(size 0.7 0.7)
					(thickness 0.15)
				)
				(justify left bottom mirror)
			)
		)
		(fp_text user "Author: Antmicro"
			(at -0.939 -3.399 0)
			(layer "B.Fab")
			(effects
				(font
					(size 0.7 0.7)
					(thickness 0.15)
				)
				(justify left bottom mirror)
			)
		)
		(pad "1" smd roundrect
			(at -0.48 0 180)
			(size 0.59 0.64)
			(layers "B.Cu" "B.Mask" "B.Paste")
			(roundrect_rratio 0.25)
			(net 649 "VDD")
			(pintype "passive")
		)
		(pad "2" smd roundrect
			(at 0.48 0 180)
			(size 0.59 0.64)
			(layers "B.Cu" "B.Mask" "B.Paste")
			(roundrect_rratio 0.25)
			(net 417 "GND")
			(pintype "passive")
		)
	)
)
